(kicad_pcb
	(version 20260206)
	(generator "pcbnew")
	(generator_version "10.0")
	(general
		(thickness 1.6)
		(legacy_teardrops no)
	)
	(paper "A4")
	(title_block
		(title "v1-chassis-manager — T6M_CM_d_v01_1031_1645.brd")
		(comment 1 "Open CloudServer (Microsoft) / footprints 1019-1028 of 2512")
	)
	(layers
		(0 "F.Cu" signal "TOP")
		(4 "In1.Cu" signal "GND1")
		(6 "In2.Cu" signal "IN1")
		(8 "In3.Cu" signal "VCC1")
		(10 "In4.Cu" signal "VCC2")
		(12 "In5.Cu" signal "GND2")
		(14 "In6.Cu" signal "IN2")
		(16 "In7.Cu" signal "IN3")
		(18 "In8.Cu" signal "GND3")
		(2 "B.Cu" signal "BOTTOM")
		(9 "F.Adhes" user "F.Adhesive")
		(11 "B.Adhes" user "B.Adhesive")
		(13 "F.Paste" user "Package Geometry/Pastemask Top")
		(15 "B.Paste" user "Package Geometry/Pastemask Bottom")
		(5 "F.SilkS" user "Ref Des/Silkscreen Top")
		(7 "B.SilkS" user "Ref Des/Silkscreen Bottom")
		(1 "F.Mask" user "Board Geometry/Soldermask Top")
		(3 "B.Mask" user "Board Geometry/Soldermask Bottom")
		(17 "Dwgs.User" user "User.Drawings")
		(19 "Cmts.User" user "User.Comments")
		(21 "Eco1.User" user "User.Eco1")
		(23 "Eco2.User" user "User.Eco2")
		(25 "Edge.Cuts" user "Board Geometry/Outline")
		(27 "Margin" user)
		(31 "F.CrtYd" user "Package Geometry/Place Bound Top")
		(29 "B.CrtYd" user "Package Geometry/Place Bound Bottom")
		(35 "F.Fab" user "Ref Des/Assembly Top")
		(33 "B.Fab" user "Ref Des/Assembly Bottom")
	)
	(footprint ""
		(layer "F.Cu")
		(at 112.320578 -160.17748 90)
		(property "Reference" "R1283"
			(at 0.676148 1.209802 0)
			(unlocked yes)
			(layer "F.SilkS")
			(effects
				(font
					(size 0.635 0.4064)
					(thickness 0.1524)
				)
				(justify left)
			)
		)
		(property "Value" ""
			(at 0 0 90)
			(layer "F.Fab")
			(effects
				(font
					(size 1.27 1.27)
				)
			)
		)
		(duplicate_pad_numbers_are_jumpers no)
		(fp_line
			(start 0.7874 -0.4064)
			(end 0.7874 0.4064)
			(stroke
				(width 0.1524)
				(type default)
			)
			(layer "F.SilkS")
		)
		(fp_line
			(start -0.7874 -0.4064)
			(end 0.7874 -0.4064)
			(stroke
				(width 0.1524)
				(type default)
			)
			(layer "F.SilkS")
		)
		(fp_line
			(start 0.7874 0.4064)
			(end -0.7874 0.4064)
			(stroke
				(width 0.1524)
				(type default)
			)
			(layer "F.SilkS")
		)
		(fp_line
			(start -0.7874 0.4064)
			(end -0.7874 -0.4064)
			(stroke
				(width 0.1524)
				(type default)
			)
			(layer "F.SilkS")
		)
		(fp_poly
			(pts
				(xy -0.508 0.2794) (xy -0.508 0.2286) (xy -0.635 0.2286) (xy -0.635 -0.254) (xy -0.5334 -0.254)
				(xy -0.5334 -0.2794) (xy 0.5334 -0.2794) (xy 0.5334 -0.254) (xy 0.635 -0.254) (xy 0.635 0.254) (xy 0.5334 0.254)
				(xy 0.5334 0.2794)
			)
			(stroke
				(width 0)
				(type default)
			)
			(fill no)
			(layer "F.CrtYd")
		)
		(pad "1" smd rect
			(at 0.40005 0 90)
			(size 0.4572 0.508)
			(layers "F.Cu" "F.Mask" "F.Paste")
			(net "P5V_NODE1")
		)
		(pad "2" smd rect
			(at -0.40005 0 90)
			(size 0.4572 0.508)
			(layers "F.Cu" "F.Mask" "F.Paste")
			(net "PMBUS2_EN")
		)
	)
	(footprint ""
		(layer "F.Cu")
		(at 122.66676 -188.126624 90)
		(property "Reference" "C632"
			(at 4.912868 -0.284988 90)
			(unlocked yes)
			(layer "F.SilkS")
			(effects
				(font
					(size 0.7874 0.5842)
					(thickness 0.1524)
				)
				(justify left)
			)
		)
		(property "Value" ""
			(at 0 0 90)
			(layer "F.Fab")
			(effects
				(font
					(size 1.27 1.27)
				)
			)
		)
		(duplicate_pad_numbers_are_jumpers no)
		(fp_line
			(start 0.7874 -0.4064)
			(end 0.7874 0.4064)
			(stroke
				(width 0.1524)
				(type default)
			)
			(layer "F.SilkS")
		)
		(fp_line
			(start -0.7874 -0.4064)
			(end 0.7874 -0.4064)
			(stroke
				(width 0.1524)
				(type default)
			)
			(layer "F.SilkS")
		)
		(fp_line
			(start 0 0.381)
			(end 0 -0.381)
			(stroke
				(width 0.1524)
				(type default)
			)
			(layer "F.SilkS")
		)
		(fp_line
			(start 0.7874 0.4064)
			(end -0.7874 0.4064)
			(stroke
				(width 0.1524)
				(type default)
			)
			(layer "F.SilkS")
		)
		(fp_line
			(start -0.7874 0.4064)
			(end -0.7874 -0.4064)
			(stroke
				(width 0.1524)
				(type default)
			)
			(layer "F.SilkS")
		)
		(fp_poly
			(pts
				(xy -0.5334 0.254) (xy -0.635 0.254) (xy -0.635 0.2286) (xy -0.635 -0.254) (xy -0.5334 -0.254) (xy -0.5334 -0.2794)
				(xy 0.5334 -0.2794) (xy 0.5334 -0.254) (xy 0.635 -0.254) (xy 0.635 0.254) (xy 0.5334 0.254) (xy 0.5334 0.2794)
				(xy -0.508 0.2794) (xy -0.5334 0.2794)
			)
			(stroke
				(width 0)
				(type default)
			)
			(fill no)
			(layer "F.CrtYd")
		)
		(pad "1" smd rect
			(at 0.40005 0 90)
			(size 0.4572 0.508)
			(layers "F.Cu" "F.Mask" "F.Paste")
			(net "T8_NODE4_EN_R")
		)
		(pad "2" smd rect
			(at -0.40005 0 90)
			(size 0.4572 0.508)
			(layers "F.Cu" "F.Mask" "F.Paste")
			(net "GND")
		)
	)
	(footprint ""
		(layer "F.Cu")
		(at 81.39176 -185.205624 -90)
		(property "Reference" "R898"
			(at -4.198112 1.795272 90)
			(unlocked yes)
			(layer "F.SilkS")
			(effects
				(font
					(size 0.7874 0.5842)
					(thickness 0.1524)
				)
				(justify left)
			)
		)
		(property "Value" ""
			(at 0 0 270)
			(layer "F.Fab")
			(effects
				(font
					(size 1.27 1.27)
				)
			)
		)
		(duplicate_pad_numbers_are_jumpers no)
		(fp_line
			(start -0.7874 0.4064)
			(end -0.7874 -0.4064)
			(stroke
				(width 0.1524)
				(type default)
			)
			(layer "F.SilkS")
		)
		(fp_line
			(start 0.7874 0.4064)
			(end -0.7874 0.4064)
			(stroke
				(width 0.1524)
				(type default)
			)
			(layer "F.SilkS")
		)
		(fp_line
			(start -0.7874 -0.4064)
			(end 0.7874 -0.4064)
			(stroke
				(width 0.1524)
				(type default)
			)
			(layer "F.SilkS")
		)
		(fp_line
			(start 0.7874 -0.4064)
			(end 0.7874 0.4064)
			(stroke
				(width 0.1524)
				(type default)
			)
			(layer "F.SilkS")
		)
		(fp_poly
			(pts
				(xy -0.508 0.2794) (xy -0.508 0.2286) (xy -0.635 0.2286) (xy -0.635 -0.254) (xy -0.5334 -0.254)
				(xy -0.5334 -0.2794) (xy 0.5334 -0.2794) (xy 0.5334 -0.254) (xy 0.635 -0.254) (xy 0.635 0.254) (xy 0.5334 0.254)
				(xy 0.5334 0.2794)
			)
			(stroke
				(width 0)
				(type default)
			)
			(fill no)
			(layer "F.CrtYd")
		)
		(pad "1" smd rect
			(at 0.40005 0 270)
			(size 0.4572 0.508)
			(layers "F.Cu" "F.Mask" "F.Paste")
			(net "T4_NODE2_EN")
		)
		(pad "2" smd rect
			(at -0.40005 0 270)
			(size 0.4572 0.508)
			(layers "F.Cu" "F.Mask" "F.Paste")
			(net "T4_NODE2_EN_R")
		)
	)
	(footprint ""
		(layer "F.Cu")
		(at 176.666398 -37.991034)
		(property "Reference" "C557"
			(at -4.146042 0.705612 0)
			(unlocked yes)
			(layer "F.SilkS")
			(effects
				(font
					(size 0.7874 0.5842)
					(thickness 0.1524)
				)
				(justify left)
			)
		)
		(property "Value" ""
			(at 0 0 0)
			(layer "F.Fab")
			(effects
				(font
					(size 1.27 1.27)
				)
			)
		)
		(duplicate_pad_numbers_are_jumpers no)
		(fp_line
			(start -0.7874 -0.4064)
			(end 0.7874 -0.4064)
			(stroke
				(width 0.1524)
				(type default)
			)
			(layer "F.SilkS")
		)
		(fp_line
			(start -0.7874 0.4064)
			(end -0.7874 -0.4064)
			(stroke
				(width 0.1524)
				(type default)
			)
			(layer "F.SilkS")
		)
		(fp_line
			(start 0 0.381)
			(end 0 -0.381)
			(stroke
				(width 0.1524)
				(type default)
			)
			(layer "F.SilkS")
		)
		(fp_line
			(start 0.7874 -0.4064)
			(end 0.7874 0.4064)
			(stroke
				(width 0.1524)
				(type default)
			)
			(layer "F.SilkS")
		)
		(fp_line
			(start 0.7874 0.4064)
			(end -0.7874 0.4064)
			(stroke
				(width 0.1524)
				(type default)
			)
			(layer "F.SilkS")
		)
		(fp_poly
			(pts
				(xy -0.5334 0.254) (xy -0.635 0.254) (xy -0.635 0.2286) (xy -0.635 -0.254) (xy -0.5334 -0.254) (xy -0.5334 -0.2794)
				(xy 0.5334 -0.2794) (xy 0.5334 -0.254) (xy 0.635 -0.254) (xy 0.635 0.254) (xy 0.5334 0.254) (xy 0.5334 0.2794)
				(xy -0.508 0.2794) (xy -0.5334 0.2794)
			)
			(stroke
				(width 0)
				(type default)
			)
			(fill no)
			(layer "F.CrtYd")
		)
		(pad "1" smd rect
			(at 0.40005 0)
			(size 0.4572 0.508)
			(layers "F.Cu" "F.Mask" "F.Paste")
			(net "USBPWR_P0")
		)
		(pad "2" smd rect
			(at -0.40005 0)
			(size 0.4572 0.508)
			(layers "F.Cu" "F.Mask" "F.Paste")
			(net "GND")
		)
	)
	(footprint ""
		(layer "F.Cu")
		(at 171.852336 -131.92125 180)
		(property "Reference" "R93"
			(at 1.965452 8.565896 0)
			(unlocked yes)
			(layer "F.SilkS")
			(effects
				(font
					(size 0.7874 0.5842)
					(thickness 0.1524)
				)
				(justify left)
			)
		)
		(property "Value" ""
			(at 0 0 180)
			(layer "F.Fab")
			(effects
				(font
					(size 1.27 1.27)
				)
			)
		)
		(duplicate_pad_numbers_are_jumpers no)
		(fp_line
			(start 0.7874 0.4064)
			(end -0.7874 0.4064)
			(stroke
				(width 0.1524)
				(type default)
			)
			(layer "F.SilkS")
		)
		(fp_line
			(start 0.7874 -0.4064)
			(end 0.7874 0.4064)
			(stroke
				(width 0.1524)
				(type default)
			)
			(layer "F.SilkS")
		)
		(fp_line
			(start -0.7874 0.4064)
			(end -0.7874 -0.4064)
			(stroke
				(width 0.1524)
				(type default)
			)
			(layer "F.SilkS")
		)
		(fp_line
			(start -0.7874 -0.4064)
			(end 0.7874 -0.4064)
			(stroke
				(width 0.1524)
				(type default)
			)
			(layer "F.SilkS")
		)
		(fp_poly
			(pts
				(xy -0.508 0.2794) (xy -0.508 0.2286) (xy -0.635 0.2286) (xy -0.635 -0.254) (xy -0.5334 -0.254)
				(xy -0.5334 -0.2794) (xy 0.5334 -0.2794) (xy 0.5334 -0.254) (xy 0.635 -0.254) (xy 0.635 0.254) (xy 0.5334 0.254)
				(xy 0.5334 0.2794)
			)
			(stroke
				(width 0)
				(type default)
			)
			(fill no)
			(layer "F.CrtYd")
		)
		(pad "1" smd rect
			(at 0.40005 0 180)
			(size 0.4572 0.508)
			(layers "F.Cu" "F.Mask" "F.Paste")
			(net "H_CPU_NODE1_THRMTRIP_L")
		)
		(pad "2" smd rect
			(at -0.40005 0 180)
			(size 0.4572 0.508)
			(layers "F.Cu" "F.Mask" "F.Paste")
			(net "N41777073")
		)
	)
	(footprint ""
		(layer "F.Cu")
		(at 149.508972 -33.586928 180)
		(property "Reference" "R650"
			(at 1.179576 3.705352 0)
			(unlocked yes)
			(layer "F.SilkS")
			(effects
				(font
					(size 0.7874 0.5842)
					(thickness 0.1524)
				)
				(justify left)
			)
		)
		(property "Value" ""
			(at 0 0 180)
			(layer "F.Fab")
			(effects
				(font
					(size 1.27 1.27)
				)
			)
		)
		(duplicate_pad_numbers_are_jumpers no)
		(fp_line
			(start 0.7874 0.4064)
			(end -0.7874 0.4064)
			(stroke
				(width 0.1524)
				(type default)
			)
			(layer "F.SilkS")
		)
		(fp_line
			(start 0.7874 -0.4064)
			(end 0.7874 0.4064)
			(stroke
				(width 0.1524)
				(type default)
			)
			(layer "F.SilkS")
		)
		(fp_line
			(start -0.7874 0.4064)
			(end -0.7874 -0.4064)
			(stroke
				(width 0.1524)
				(type default)
			)
			(layer "F.SilkS")
		)
		(fp_line
			(start -0.7874 -0.4064)
			(end 0.7874 -0.4064)
			(stroke
				(width 0.1524)
				(type default)
			)
			(layer "F.SilkS")
		)
		(fp_poly
			(pts
				(xy -0.508 0.2794) (xy -0.508 0.2286) (xy -0.635 0.2286) (xy -0.635 -0.254) (xy -0.5334 -0.254)
				(xy -0.5334 -0.2794) (xy 0.5334 -0.2794) (xy 0.5334 -0.254) (xy 0.635 -0.254) (xy 0.635 0.254) (xy 0.5334 0.254)
				(xy 0.5334 0.2794)
			)
			(stroke
				(width 0)
				(type default)
			)
			(fill no)
			(layer "F.CrtYd")
		)
		(pad "1" smd rect
			(at 0.40005 0 180)
			(size 0.4572 0.508)
			(layers "F.Cu" "F.Mask" "F.Paste")
			(net "P3V3_NODE1")
		)
		(pad "2" smd rect
			(at -0.40005 0 180)
			(size 0.4572 0.508)
			(layers "F.Cu" "F.Mask" "F.Paste")
			(net "N21624806")
		)
	)
	(footprint ""
		(layer "F.Cu")
		(at 184.3786 -179.7812)
		(property "Reference" "R1318"
			(at 9.3218 17.19707 0)
			(unlocked yes)
			(layer "F.SilkS")
			(effects
				(font
					(size 0.7874 0.5842)
					(thickness 0.1524)
				)
				(justify left)
			)
		)
		(property "Value" ""
			(at 0 0 0)
			(layer "F.Fab")
			(effects
				(font
					(size 1.27 1.27)
				)
			)
		)
		(duplicate_pad_numbers_are_jumpers no)
		(fp_line
			(start -0.7874 -0.4064)
			(end 0.7874 -0.4064)
			(stroke
				(width 0.1524)
				(type default)
			)
			(layer "F.SilkS")
		)
		(fp_line
			(start -0.7874 0.4064)
			(end -0.7874 -0.4064)
			(stroke
				(width 0.1524)
				(type default)
			)
			(layer "F.SilkS")
		)
		(fp_line
			(start 0.7874 -0.4064)
			(end 0.7874 0.4064)
			(stroke
				(width 0.1524)
				(type default)
			)
			(layer "F.SilkS")
		)
		(fp_line
			(start 0.7874 0.4064)
			(end -0.7874 0.4064)
			(stroke
				(width 0.1524)
				(type default)
			)
			(layer "F.SilkS")
		)
		(fp_poly
			(pts
				(xy -0.508 0.2794) (xy -0.508 0.2286) (xy -0.635 0.2286) (xy -0.635 -0.254) (xy -0.5334 -0.254)
				(xy -0.5334 -0.2794) (xy 0.5334 -0.2794) (xy 0.5334 -0.254) (xy 0.635 -0.254) (xy 0.635 0.254) (xy 0.5334 0.254)
				(xy 0.5334 0.2794)
			)
			(stroke
				(width 0)
				(type default)
			)
			(fill no)
			(layer "F.CrtYd")
		)
		(pad "1" smd rect
			(at 0.40005 0)
			(size 0.4572 0.508)
			(layers "F.Cu" "F.Mask" "F.Paste")
			(net "POWER_SW3_PWR_CTR_12V")
		)
		(pad "2" smd rect
			(at -0.40005 0)
			(size 0.4572 0.508)
			(layers "F.Cu" "F.Mask" "F.Paste")
			(net "POWER_SW3_PWR_CTR_12V_R")
		)
	)
	(footprint ""
		(layer "F.Cu")
		(at 108.390944 -162.73272 180)
		(property "Reference" "R646"
			(at -86.581996 -70.245732 0)
			(unlocked yes)
			(layer "F.SilkS")
			(effects
				(font
					(size 0.7874 0.5842)
					(thickness 0.1524)
				)
				(justify left)
			)
		)
		(property "Value" ""
			(at 0 0 180)
			(layer "F.Fab")
			(effects
				(font
					(size 1.27 1.27)
				)
			)
		)
		(duplicate_pad_numbers_are_jumpers no)
		(fp_line
			(start 0.7874 0.4064)
			(end -0.7874 0.4064)
			(stroke
				(width 0.1524)
				(type default)
			)
			(layer "F.SilkS")
		)
		(fp_line
			(start 0.7874 -0.4064)
			(end 0.7874 0.4064)
			(stroke
				(width 0.1524)
				(type default)
			)
			(layer "F.SilkS")
		)
		(fp_line
			(start -0.7874 0.4064)
			(end -0.7874 -0.4064)
			(stroke
				(width 0.1524)
				(type default)
			)
			(layer "F.SilkS")
		)
		(fp_line
			(start -0.7874 -0.4064)
			(end 0.7874 -0.4064)
			(stroke
				(width 0.1524)
				(type default)
			)
			(layer "F.SilkS")
		)
		(fp_poly
			(pts
				(xy -0.508 0.2794) (xy -0.508 0.2286) (xy -0.635 0.2286) (xy -0.635 -0.254) (xy -0.5334 -0.254)
				(xy -0.5334 -0.2794) (xy 0.5334 -0.2794) (xy 0.5334 -0.254) (xy 0.635 -0.254) (xy 0.635 0.254) (xy 0.5334 0.254)
				(xy 0.5334 0.2794)
			)
			(stroke
				(width 0)
				(type default)
			)
			(fill no)
			(layer "F.CrtYd")
		)
		(pad "1" smd rect
			(at 0.40005 0 180)
			(size 0.4572 0.508)
			(layers "F.Cu" "F.Mask" "F.Paste")
			(net "I2C_PSU2_SCL")
		)
		(pad "2" smd rect
			(at -0.40005 0 180)
			(size 0.4572 0.508)
			(layers "F.Cu" "F.Mask" "F.Paste")
			(net "I2C_PSU2_SCL_MOS")
		)
	)
	(footprint ""
		(layer "F.Cu")
		(at 190.173102 -28.98775 90)
		(property "Reference" "FS3"
			(at -0.15367 1.844802 90)
			(unlocked yes)
			(layer "F.SilkS")
			(effects
				(font
					(size 0.7874 0.5842)
					(thickness 0.1524)
				)
				(justify left)
			)
		)
		(property "Value" ""
			(at 0 0 90)
			(layer "F.Fab")
			(effects
				(font
					(size 1.27 1.27)
				)
			)
		)
		(duplicate_pad_numbers_are_jumpers no)
		(fp_line
			(start 3.550412 -1.050036)
			(end 3.550412 1.050036)
			(stroke
				(width 0.1524)
				(type default)
			)
			(layer "F.SilkS")
		)
		(fp_line
			(start -0.650494 -1.050036)
			(end 3.550412 -1.050036)
			(stroke
				(width 0.1524)
				(type default)
			)
			(layer "F.SilkS")
		)
		(fp_line
			(start 3.550412 1.050036)
			(end -0.650494 1.050036)
			(stroke
				(width 0.1524)
				(type default)
			)
			(layer "F.SilkS")
		)
		(fp_line
			(start -0.650494 1.050036)
			(end -0.650494 -1.050036)
			(stroke
				(width 0.1524)
				(type default)
			)
			(layer "F.SilkS")
		)
		(fp_poly
			(pts
				(xy 3.228086 -0.9652) (xy 3.228086 -1.100074) (xy -0.327914 -1.100074) (xy -0.327914 -0.9652) (xy -0.556514 -0.9652)
				(xy -0.556514 0.9652) (xy -0.327914 0.9652) (xy -0.327914 1.100074) (xy 3.228086 1.100074) (xy 3.228086 0.9652)
				(xy 3.456686 0.9652) (xy 3.456686 -0.9652)
			)
			(stroke
				(width 0)
				(type default)
			)
			(fill no)
			(layer "F.CrtYd")
		)
		(fp_text user "1"
			(at -1.177036 -0.36449 90)
			(unlocked yes)
			(layer "F.SilkS")
			(effects
				(font
					(size 0.635 0.4064)
					(thickness 0.1524)
				)
				(justify left)
			)
		)
		(fp_text user "2"
			(at 3.635248 2.086864 0)
			(unlocked yes)
			(layer "F.SilkS")
			(effects
				(font
					(size 0.635 0.4064)
					(thickness 0.1524)
				)
				(justify left)
			)
		)
		(pad "1" smd rect
			(at 0 0 90)
			(size 1.016 1.8034)
			(layers "F.Cu" "F.Mask" "F.Paste")
			(net "P5V_NODE1")
		)
		(pad "2" smd rect
			(at 2.899918 0 90)
			(size 1.016 1.8034)
			(layers "F.Cu" "F.Mask" "F.Paste")
			(net "USBPWR_P0")
		)
	)
	(footprint ""
		(layer "F.Cu")
		(at 19.72564 -131.344416 180)
		(property "Reference" "PR26"
			(at -1.49352 0.232156 0)
			(unlocked yes)
			(layer "F.SilkS")
			(effects
				(font
					(size 0.7874 0.5842)
					(thickness 0.1524)
				)
				(justify left)
			)
		)
		(property "Value" ""
			(at 0 0 180)
			(layer "F.Fab")
			(effects
				(font
					(size 1.27 1.27)
				)
			)
		)
		(duplicate_pad_numbers_are_jumpers no)
		(fp_line
			(start 0.7874 0.4064)
			(end -0.7874 0.4064)
			(stroke
				(width 0.1524)
				(type default)
			)
			(layer "F.SilkS")
		)
		(fp_line
			(start 0.7874 -0.4064)
			(end 0.7874 0.4064)
			(stroke
				(width 0.1524)
				(type default)
			)
			(layer "F.SilkS")
		)
		(fp_line
			(start -0.7874 0.4064)
			(end -0.7874 -0.4064)
			(stroke
				(width 0.1524)
				(type default)
			)
			(layer "F.SilkS")
		)
		(fp_line
			(start -0.7874 -0.4064)
			(end 0.7874 -0.4064)
			(stroke
				(width 0.1524)
				(type default)
			)
			(layer "F.SilkS")
		)
		(fp_poly
			(pts
				(xy -0.508 0.2794) (xy -0.508 0.2286) (xy -0.635 0.2286) (xy -0.635 -0.254) (xy -0.5334 -0.254)
				(xy -0.5334 -0.2794) (xy 0.5334 -0.2794) (xy 0.5334 -0.254) (xy 0.635 -0.254) (xy 0.635 0.254) (xy 0.5334 0.254)
				(xy 0.5334 0.2794)
			)
			(stroke
				(width 0)
				(type default)
			)
			(fill no)
			(layer "F.CrtYd")
		)
		(pad "1" smd rect
			(at 0.40005 0 180)
			(size 0.4572 0.508)
			(layers "F.Cu" "F.Mask" "F.Paste")
			(net "P1V05_NODE1_MODE")
		)
		(pad "2" smd rect
			(at -0.40005 0 180)
			(size 0.4572 0.508)
			(layers "F.Cu" "F.Mask" "F.Paste")
			(net "GND")
		)
	)
)
